FILE_TYPE = CONNECTIVITY;
{Allegro Design Entry HDL 17.4-2019 S026 (4007227) 1/17/2022}
"PAGE_NUMBER" = 132;
0"NC";
1"GND\g";
2"GND\g";
3"PVDD18_S5_P0\g";
4"P3V3_AUX\g";
5"IRQ_OCP_V3_2_WAKE_BUF_N";
6"IRQ_OCP_SFF_WAKE_BUF_N";
7"IRQ_LVC3_WAKE_N";
8"M2_0_PEWAKE_R_N";
9"IRQ_WAKE_R_N";
10"IRQ_WAKE_N";
11"IRQ_LVC3_WAKE";
12"P3V3_AUX\g";
13"IRQ_LVC3_WAKE";
%"Q_RES"
"1","(-3075,4125)","2","pure_quanta","I10";
;
LOCATION"R1009"
$SEC"1"
CDS_SEC"1"
PACK_TYPE"0402LF"
VALUE"10K"
MATERIAL"CHIP"
TOLERANCE"1%"
WATTAGE"1/16W"
CDS_LIB"pure_quanta"
PART_NUMBER"CS31002FB08";
"B"
$PN"2"11;
"A"
$PN"1"12;
%"UNIVERSAL_GND"
"1","(-2950,4500)","7","pure_quanta_power","I11";
;
CDS_LIB"pure_quanta_power"
HDL_POWER"GND";
"A"1;
%"MOSFET_DUAL_6P"
"1","(-2475,4450)","0","pure_quanta","I12";
;
LOCATION"Q4"
$SEC"1"
CDS_SEC"1"
VALUE"2N7002KDW"
MATERIAL"IC"
PART_TYPE"SMLF"
CDS_LIB"pure_quanta"
NEEDS_NO_SIZE"TRUE"
CDS_LMAN_SYM_OUTLINE"-150,100,150,-100"
PART_NUMBER"BAM70020047";
"D2"
$PN"3"9;
"D1"
$PN"6"11;
"S2"
$PN"4"2;
"S1"
$PN"1"1;
"G2"
$PN"5"13;
"G1"
$PN"2"7;
%"UNIVERSAL_POWER"
"1","(-2725,4275)","0","pure_quanta_power","I13";
;
HDL_POWER"P3V3_AUX"
CDS_LIB"pure_quanta_power";
"A"12;
%"UNIVERSAL_GND"
"1","(-2075,4500)","1","pure_quanta_power","I14";
;
CDS_LIB"pure_quanta_power"
HDL_POWER"GND";
"A"2;
%"Q_RES"
"1","(-1525,4400)","0","pure_quanta","I16";
;
LOCATION"R1311"
$SEC"1"
CDS_SEC"1"
VALUE"33"
TOLERANCE"5%"
CDS_LIB"pure_quanta"
WATTAGE"1/16W"
MATERIAL"CHIP"
PACK_TYPE"0402LF"
PART_NUMBER"CS03302JB10";
"B"
$PN"2"10;
"A"
$PN"1"9;
%"Q_RES"
"2","(-1175,4650)","0","pure_quanta","I18";
;
LOCATION"R437"
$SEC"1"
CDS_SEC"1"
PACK_TYPE"0402LF"
VALUE"2.2K"
TOLERANCE"5%"
MATERIAL"CHIP"
WATTAGE"1/16W"
CDS_LIB"pure_quanta"
PART_NUMBER"CS22202JB07";
"A"
$PN"1"3;
"B"
$PN"2"10;
%"UNIVERSAL_POWER"
"1","(-1175,4850)","0","pure_quanta_power","I19";
;
HDL_POWER"PVDD18_S5_P0"
CDS_LIB"pure_quanta_power";
"A"3;
%"Q_RES"
"1","(-5925,2975)","0","pure_quanta","I4";
;
LOCATION"R1005"
$SEC"1"
CDS_SEC"1"
VALUE"33"
TOLERANCE"5%"
CDS_LIB"pure_quanta"
WATTAGE"1/16W"
MATERIAL"CHIP"
PACK_TYPE"0402LF"
PART_NUMBER"CS03302JB10";
"B"
$PN"2"7;
"A"
$PN"1"8;
%"Q_RES"
"1","(-5925,3450)","0","pure_quanta","I5";
;
LOCATION"R116"
$SEC"1"
CDS_SEC"1"
VALUE"33"
PACK_TYPE"0402LF"
WATTAGE"1/16W"
MATERIAL"CHIP"
TOLERANCE"5%"
CDS_LIB"pure_quanta"
BOM_COST"PCH"
PART_NUMBER"CS03302JB10";
"B"
$PN"2"7;
"A"
$PN"1"6;
%"Q_RES"
"1","(-5925,3275)","0","pure_quanta","I6";
;
LOCATION"R6063"
$SEC"1"
CDS_SEC"1"
MATERIAL"CHIP"
VALUE"33"
PACK_TYPE"0402LF"
WATTAGE"1/16W"
TOLERANCE"5%"
BOM_COST"PCH"
CDS_LIB"pure_quanta"
PART_NUMBER"CS03302JB10";
"B"
$PN"2"7;
"A"
$PN"1"5;
%"Q_RES"
"2","(-4250,4675)","2","pure_quanta","I7";
;
LOCATION"R994"
$SEC"1"
CDS_SEC"1"
TOLERANCE"1%"
PACK_TYPE"0402LF"
MATERIAL"CHIP"
VALUE"10K"
WATTAGE"1/16W"
CDS_LIB"pure_quanta"
PART_NUMBER"CS31002FB08";
"A"
$PN"1"4;
"B"
$PN"2"7;
%"UNIVERSAL_POWER"
"1","(-4250,4925)","0","pure_quanta_power","I8";
;
HDL_POWER"P3V3_AUX"
CDS_LIB"pure_quanta_power";
"A"4;
END.
